# S9S_MB_2U (Grand Teton) — schematic netlist excerpt (pin names and nets, part order shuffled) for the footprints in the layout excerpt that follows; sources: Cadence DE-HDL packaged netlist, KiCad conversion of 03242023_DA0F0TMBIJ0_F0T_Motherboard_J_brd_V01_OCP.brd

C2249  Q_CAP  0.1UF 25V 10% X7R  pkg 0402  page 226 : A = P0V62_CPU0_ERRS_VREF ; B = GND
R4611  Q_RES  33.2 1% CHIP  pkg 0402LF  page 214 : A = FM_BMC_CPU_FBRK_OUT_R_N ; B = FM_BMC_CPU_FBRK_OUT_N

(kicad_pcb
	(version 20260206)
	(generator "pcbnew")
	(generator_version "10.0")
	(general
		(thickness 1.6)
		(legacy_teardrops no)
	)
	(paper "A4")
	(title_block
		(title "03242023_DA0F0TMBIJ0_F0T_Motherboard_J_brd_V01_OCP.brd")
		(comment 1 "Grand Teton / footprints 4151-4152 of 6105")
	)
	(layers
		(0 "F.Cu" signal "TOP")
		(4 "In1.Cu" signal "GND")
		(6 "In2.Cu" signal "IN1")
		(8 "In3.Cu" signal "GND1")
		(10 "In4.Cu" signal "IN2")
		(12 "In5.Cu" signal "GND2")
		(14 "In6.Cu" signal "IN3")
		(16 "In7.Cu" signal "GND3")
		(18 "In8.Cu" signal "VCC")
		(20 "In9.Cu" signal "VCC1")
		(22 "In10.Cu" signal "GND4")
		(24 "In11.Cu" signal "IN4")
		(26 "In12.Cu" signal "GND5")
		(28 "In13.Cu" signal "IN5")
		(30 "In14.Cu" signal "GND6")
		(32 "In15.Cu" signal "IN6")
		(34 "In16.Cu" signal "GND7")
		(2 "B.Cu" signal "BOTTOM")
		(9 "F.Adhes" user "F.Adhesive")
		(11 "B.Adhes" user "B.Adhesive")
		(13 "F.Paste" user "Package Geometry/Pastemask Top")
		(15 "B.Paste" user "Package Geometry/Pastemask Bottom")
		(5 "F.SilkS" user "Ref Des/Silkscreen Top")
		(7 "B.SilkS" user "Ref Des/Silkscreen Bottom")
		(1 "F.Mask" user "Board Geometry/Soldermask Top")
		(3 "B.Mask" user "Board Geometry/Soldermask Bottom")
		(17 "Dwgs.User" user "User.Drawings")
		(19 "Cmts.User" user "User.Comments")
		(21 "Eco1.User" user "User.Eco1")
		(23 "Eco2.User" user "User.Eco2")
		(25 "Edge.Cuts" user "Board Geometry/Outline")
		(27 "Margin" user)
		(31 "F.CrtYd" user "Package Geometry/Place Bound Top")
		(29 "B.CrtYd" user "Package Geometry/Place Bound Bottom")
		(35 "F.Fab" user "Ref Des/Assembly Top")
		(33 "B.Fab" user "Ref Des/Assembly Bottom")
	)
	(footprint ""
		(layer "F.Cu")
		(at 196.07784 -92.832428 90)
		(property "Reference" "R4611"
			(at 0 0 90)
			(layer "F.SilkS")
			(hide yes)
			(effects
				(font
					(size 1.27 1.27)
				)
			)
		)
		(property "Value" ""
			(at 0 0 90)
			(layer "F.Fab")
			(effects
				(font
					(size 1.27 1.27)
				)
			)
		)
		(duplicate_pad_numbers_are_jumpers no)
		(fp_line
			(start 0.7874 -0.4064)
			(end 0.7874 0.4064)
			(stroke
				(width 0.1524)
				(type default)
			)
			(layer "F.SilkS")
		)
		(fp_line
			(start -0.7874 -0.4064)
			(end 0.7874 -0.4064)
			(stroke
				(width 0.1524)
				(type default)
			)
			(layer "F.SilkS")
		)
		(fp_line
			(start 0.7874 0.4064)
			(end -0.7874 0.4064)
			(stroke
				(width 0.1524)
				(type default)
			)
			(layer "F.SilkS")
		)
		(fp_line
			(start -0.7874 0.4064)
			(end -0.7874 -0.4064)
			(stroke
				(width 0.1524)
				(type default)
			)
			(layer "F.SilkS")
		)
		(fp_line
			(start -0.12065 -0.305054)
			(end -0.12065 -0.2794)
			(stroke
				(width 0.1)
				(type default)
			)
			(layer "F.Fab")
		)
		(fp_line
			(start -0.67945 -0.305054)
			(end -0.12065 -0.305054)
			(stroke
				(width 0.1)
				(type default)
			)
			(layer "F.Fab")
		)
		(fp_line
			(start 0.67945 -0.3048)
			(end 0.67945 0.3048)
			(stroke
				(width 0.1)
				(type default)
			)
			(layer "F.Fab")
		)
		(fp_line
			(start 0.12065 -0.3048)
			(end 0.67945 -0.3048)
			(stroke
				(width 0.1)
				(type default)
			)
			(layer "F.Fab")
		)
		(fp_line
			(start 0.12065 -0.2794)
			(end 0.12065 -0.3048)
			(stroke
				(width 0.1)
				(type default)
			)
			(layer "F.Fab")
		)
		(fp_line
			(start -0.12065 -0.2794)
			(end 0.12065 -0.2794)
			(stroke
				(width 0.1)
				(type default)
			)
			(layer "F.Fab")
		)
		(fp_line
			(start 0.120396 0.2794)
			(end -0.12065 0.2794)
			(stroke
				(width 0.1)
				(type default)
			)
			(layer "F.Fab")
		)
		(fp_line
			(start -0.12065 0.2794)
			(end -0.12065 0.3048)
			(stroke
				(width 0.1)
				(type default)
			)
			(layer "F.Fab")
		)
		(fp_line
			(start 0.67945 0.3048)
			(end 0.120396 0.3048)
			(stroke
				(width 0.1)
				(type default)
			)
			(layer "F.Fab")
		)
		(fp_line
			(start 0.120396 0.3048)
			(end 0.120396 0.2794)
			(stroke
				(width 0.1)
				(type default)
			)
			(layer "F.Fab")
		)
		(fp_line
			(start -0.12065 0.3048)
			(end -0.67945 0.3048)
			(stroke
				(width 0.1)
				(type default)
			)
			(layer "F.Fab")
		)
		(fp_line
			(start -0.67945 0.3048)
			(end -0.67945 -0.305054)
			(stroke
				(width 0.1)
				(type default)
			)
			(layer "F.Fab")
		)
		(pad "1" smd circle
			(at -0.40005 0 90)
			(size 0 0)
			(layers "F.Cu" "F.Mask" "F.Paste")
			(net "FM_BMC_CPU_FBRK_OUT_R_N")
		)
		(pad "2" smd circle
			(at 0.40005 0 90)
			(size 0 0)
			(layers "F.Cu" "F.Mask" "F.Paste")
			(net "FM_BMC_CPU_FBRK_OUT_N")
		)
	)
	(footprint ""
		(layer "F.Cu")
		(at 115.75288 -104.079548 90)
		(property "Reference" "C2249"
			(at 0 0 90)
			(layer "F.SilkS")
			(hide yes)
			(effects
				(font
					(size 1.27 1.27)
				)
			)
		)
		(property "Value" ""
			(at 0 0 90)
			(layer "F.Fab")
			(effects
				(font
					(size 1.27 1.27)
				)
			)
		)
		(duplicate_pad_numbers_are_jumpers no)
		(fp_line
			(start 0.7874 -0.4064)
			(end 0.7874 0.4064)
			(stroke
				(width 0.1524)
				(type default)
			)
			(layer "F.SilkS")
		)
		(fp_line
			(start -0.7874 -0.4064)
			(end 0.7874 -0.4064)
			(stroke
				(width 0.1524)
				(type default)
			)
			(layer "F.SilkS")
		)
		(fp_line
			(start 0.7874 0.4064)
			(end -0.7874 0.4064)
			(stroke
				(width 0.1524)
				(type default)
			)
			(layer "F.SilkS")
		)
		(fp_line
			(start -0.7874 0.4064)
			(end -0.7874 -0.4064)
			(stroke
				(width 0.1524)
				(type default)
			)
			(layer "F.SilkS")
		)
		(fp_line
			(start -0.12065 -0.305054)
			(end -0.12065 -0.2794)
			(stroke
				(width 0.1)
				(type default)
			)
			(layer "F.Fab")
		)
		(fp_line
			(start -0.67945 -0.305054)
			(end -0.12065 -0.305054)
			(stroke
				(width 0.1)
				(type default)
			)
			(layer "F.Fab")
		)
		(fp_line
			(start 0.67945 -0.3048)
			(end 0.67945 0.3048)
			(stroke
				(width 0.1)
				(type default)
			)
			(layer "F.Fab")
		)
		(fp_line
			(start 0.12065 -0.3048)
			(end 0.67945 -0.3048)
			(stroke
				(width 0.1)
				(type default)
			)
			(layer "F.Fab")
		)
		(fp_line
			(start 0.12065 -0.2794)
			(end 0.12065 -0.3048)
			(stroke
				(width 0.1)
				(type default)
			)
			(layer "F.Fab")
		)
		(fp_line
			(start -0.12065 -0.2794)
			(end 0.12065 -0.2794)
			(stroke
				(width 0.1)
				(type default)
			)
			(layer "F.Fab")
		)
		(fp_line
			(start 0.120396 0.2794)
			(end -0.12065 0.2794)
			(stroke
				(width 0.1)
				(type default)
			)
			(layer "F.Fab")
		)
		(fp_line
			(start -0.12065 0.2794)
			(end -0.12065 0.3048)
			(stroke
				(width 0.1)
				(type default)
			)
			(layer "F.Fab")
		)
		(fp_line
			(start 0.67945 0.3048)
			(end 0.120396 0.3048)
			(stroke
				(width 0.1)
				(type default)
			)
			(layer "F.Fab")
		)
		(fp_line
			(start 0.120396 0.3048)
			(end 0.120396 0.2794)
			(stroke
				(width 0.1)
				(type default)
			)
			(layer "F.Fab")
		)
		(fp_line
			(start -0.12065 0.3048)
			(end -0.67945 0.3048)
			(stroke
				(width 0.1)
				(type default)
			)
			(layer "F.Fab")
		)
		(fp_line
			(start -0.67945 0.3048)
			(end -0.67945 -0.305054)
			(stroke
				(width 0.1)
				(type default)
			)
			(layer "F.Fab")
		)
		(pad "1" smd circle
			(at -0.40005 0 90)
			(size 0 0)
			(layers "F.Cu" "F.Mask" "F.Paste")
			(net "P0V62_CPU0_ERRS_VREF")
		)
		(pad "2" smd circle
			(at 0.40005 0 90)
			(size 0 0)
			(layers "F.Cu" "F.Mask" "F.Paste")
			(net "GND")
		)
	)
)
